(kicad_pcb
	(version 20260206)
	(generator "pcbnew")
	(generator_version "10.0")
	(general
		(thickness 1.6)
		(legacy_teardrops no)
	)
	(paper "A4")
	(title_block
		(title "01162023_DA0F0TEBIF0_F0T_Expander_BD_F_brd_V02_OCP.brd")
		(comment 1 "Grand Teton / footprints 6193-6201 of 9728")
	)
	(layers
		(0 "F.Cu" signal "TOP")
		(4 "In1.Cu" signal "GND")
		(6 "In2.Cu" signal "VCC")
		(8 "In3.Cu" signal "VCC1")
		(10 "In4.Cu" signal "GND1")
		(12 "In5.Cu" signal "IN1")
		(14 "In6.Cu" signal "GND2")
		(16 "In7.Cu" signal "IN2")
		(18 "In8.Cu" signal "GND3")
		(20 "In9.Cu" signal "IN3")
		(22 "In10.Cu" signal "GND4")
		(24 "In11.Cu" signal "IN4")
		(26 "In12.Cu" signal "GND5")
		(28 "In13.Cu" signal "IN5")
		(30 "In14.Cu" signal "GND6")
		(32 "In15.Cu" signal "IN6")
		(34 "In16.Cu" signal "GND7")
		(2 "B.Cu" signal "BOTTOM")
		(9 "F.Adhes" user "F.Adhesive")
		(11 "B.Adhes" user "B.Adhesive")
		(13 "F.Paste" user "Package Geometry/Pastemask Top")
		(15 "B.Paste" user "Package Geometry/Pastemask Bottom")
		(5 "F.SilkS" user "Ref Des/Silkscreen Top")
		(7 "B.SilkS" user "Ref Des/Silkscreen Bottom")
		(1 "F.Mask" user "Board Geometry/Soldermask Top")
		(3 "B.Mask" user "Board Geometry/Soldermask Bottom")
		(17 "Dwgs.User" user "User.Drawings")
		(19 "Cmts.User" user "User.Comments")
		(21 "Eco1.User" user "User.Eco1")
		(23 "Eco2.User" user "User.Eco2")
		(25 "Edge.Cuts" user "Board Geometry/Outline")
		(27 "Margin" user)
		(31 "F.CrtYd" user "Package Geometry/Place Bound Top")
		(29 "B.CrtYd" user "Package Geometry/Place Bound Bottom")
		(35 "F.Fab" user "Ref Des/Assembly Top")
		(33 "B.Fab" user "Ref Des/Assembly Bottom")
	)
	(footprint ""
		(layer "F.Cu")
		(at 41.069768 -343.952322 90)
		(property "Reference" "C172"
			(at 0 0 90)
			(layer "F.SilkS")
			(hide yes)
			(effects
				(font
					(size 1.27 1.27)
				)
			)
		)
		(property "Value" ""
			(at 0 0 90)
			(layer "F.Fab")
			(effects
				(font
					(size 1.27 1.27)
				)
			)
		)
		(duplicate_pad_numbers_are_jumpers no)
		(fp_line
			(start 0.299974 -0.150114)
			(end 0.299974 0.150114)
			(stroke
				(width 0.1)
				(type default)
			)
			(layer "F.Fab")
		)
		(fp_line
			(start -0.299974 -0.150114)
			(end 0.299974 -0.150114)
			(stroke
				(width 0.1)
				(type default)
			)
			(layer "F.Fab")
		)
		(fp_line
			(start 0.299974 0.150114)
			(end -0.299974 0.150114)
			(stroke
				(width 0.1)
				(type default)
			)
			(layer "F.Fab")
		)
		(fp_line
			(start -0.299974 0.150114)
			(end -0.299974 -0.150114)
			(stroke
				(width 0.1)
				(type default)
			)
			(layer "F.Fab")
		)
		(pad "1" smd rect
			(at -0.2667 0 90)
			(size 0.3048 0.381)
			(layers "F.Cu" "F.Mask" "F.Paste")
			(net "P5E_PEX0_STN7_TX_DN<122>")
		)
		(pad "2" smd rect
			(at 0.2667 0 90)
			(size 0.3048 0.381)
			(layers "F.Cu" "F.Mask" "F.Paste")
			(net "P5E_PEX0_STN7_TX_C_DN<122>")
		)
	)
	(footprint ""
		(layer "F.Cu")
		(at 289.594036 -29.507688 -90)
		(property "Reference" "PC951"
			(at 0 0 270)
			(layer "F.SilkS")
			(hide yes)
			(effects
				(font
					(size 1.27 1.27)
				)
			)
		)
		(property "Value" ""
			(at 0 0 270)
			(layer "F.Fab")
			(effects
				(font
					(size 1.27 1.27)
				)
			)
		)
		(duplicate_pad_numbers_are_jumpers no)
		(fp_line
			(start -1.524 0.762)
			(end -1.524 -0.762)
			(stroke
				(width 0.1524)
				(type default)
			)
			(layer "F.SilkS")
		)
		(fp_line
			(start 1.524 0.762)
			(end -1.524 0.762)
			(stroke
				(width 0.1524)
				(type default)
			)
			(layer "F.SilkS")
		)
		(fp_line
			(start -1.524 -0.762)
			(end 1.524 -0.762)
			(stroke
				(width 0.1524)
				(type default)
			)
			(layer "F.SilkS")
		)
		(fp_line
			(start 1.524 -0.762)
			(end 1.524 0.762)
			(stroke
				(width 0.1524)
				(type default)
			)
			(layer "F.SilkS")
		)
		(fp_line
			(start -1.1049 0.724916)
			(end 1.1049 0.724916)
			(stroke
				(width 0.1)
				(type default)
			)
			(layer "F.Fab")
		)
		(fp_line
			(start 1.1049 0.724916)
			(end 1.1049 -0.724916)
			(stroke
				(width 0.1)
				(type default)
			)
			(layer "F.Fab")
		)
		(fp_line
			(start -1.1049 -0.724916)
			(end -1.1049 0.724916)
			(stroke
				(width 0.1)
				(type default)
			)
			(layer "F.Fab")
		)
		(fp_line
			(start 1.1049 -0.724916)
			(end -1.1049 -0.724916)
			(stroke
				(width 0.1)
				(type default)
			)
			(layer "F.Fab")
		)
		(pad "1" smd rect
			(at -0.889 0 90)
			(size 1.016 1.27)
			(layers "F.Cu" "F.Mask" "F.Paste")
			(net "P3V3_SSD10")
		)
		(pad "2" smd rect
			(at 0.889 0 90)
			(size 1.016 1.27)
			(layers "F.Cu" "F.Mask" "F.Paste")
			(net "GND")
		)
	)
	(footprint ""
		(layer "F.Cu")
		(at 389.81634 -343.952322 90)
		(property "Reference" "C744"
			(at 0 0 90)
			(layer "F.SilkS")
			(hide yes)
			(effects
				(font
					(size 1.27 1.27)
				)
			)
		)
		(property "Value" ""
			(at 0 0 90)
			(layer "F.Fab")
			(effects
				(font
					(size 1.27 1.27)
				)
			)
		)
		(duplicate_pad_numbers_are_jumpers no)
		(fp_line
			(start 0.299974 -0.150114)
			(end 0.299974 0.150114)
			(stroke
				(width 0.1)
				(type default)
			)
			(layer "F.Fab")
		)
		(fp_line
			(start -0.299974 -0.150114)
			(end 0.299974 -0.150114)
			(stroke
				(width 0.1)
				(type default)
			)
			(layer "F.Fab")
		)
		(fp_line
			(start 0.299974 0.150114)
			(end -0.299974 0.150114)
			(stroke
				(width 0.1)
				(type default)
			)
			(layer "F.Fab")
		)
		(fp_line
			(start -0.299974 0.150114)
			(end -0.299974 -0.150114)
			(stroke
				(width 0.1)
				(type default)
			)
			(layer "F.Fab")
		)
		(pad "1" smd rect
			(at -0.2667 0 90)
			(size 0.3048 0.381)
			(layers "F.Cu" "F.Mask" "F.Paste")
			(net "P5E_PEX3_STN5_TX_DP<88>")
		)
		(pad "2" smd rect
			(at 0.2667 0 90)
			(size 0.3048 0.381)
			(layers "F.Cu" "F.Mask" "F.Paste")
			(net "P5E_PEX3_STN5_TX_C_DP<88>")
		)
	)
	(footprint ""
		(layer "F.Cu")
		(at 336.042 -163.83 180)
		(property "Reference" "R4807"
			(at 0 0 180)
			(layer "F.SilkS")
			(hide yes)
			(effects
				(font
					(size 1.27 1.27)
				)
			)
		)
		(property "Value" ""
			(at 0 0 180)
			(layer "F.Fab")
			(effects
				(font
					(size 1.27 1.27)
				)
			)
		)
		(duplicate_pad_numbers_are_jumpers no)
		(fp_line
			(start 0.7874 0.4064)
			(end -0.7874 0.4064)
			(stroke
				(width 0.1524)
				(type default)
			)
			(layer "F.SilkS")
		)
		(fp_line
			(start 0.7874 -0.4064)
			(end 0.7874 0.4064)
			(stroke
				(width 0.1524)
				(type default)
			)
			(layer "F.SilkS")
		)
		(fp_line
			(start -0.7874 0.4064)
			(end -0.7874 -0.4064)
			(stroke
				(width 0.1524)
				(type default)
			)
			(layer "F.SilkS")
		)
		(fp_line
			(start -0.7874 -0.4064)
			(end 0.7874 -0.4064)
			(stroke
				(width 0.1524)
				(type default)
			)
			(layer "F.SilkS")
		)
		(fp_line
			(start 0.67945 0.3048)
			(end 0.120396 0.3048)
			(stroke
				(width 0.1)
				(type default)
			)
			(layer "F.Fab")
		)
		(fp_line
			(start 0.67945 -0.3048)
			(end 0.67945 0.3048)
			(stroke
				(width 0.1)
				(type default)
			)
			(layer "F.Fab")
		)
		(fp_line
			(start 0.12065 -0.2794)
			(end 0.12065 -0.3048)
			(stroke
				(width 0.1)
				(type default)
			)
			(layer "F.Fab")
		)
		(fp_line
			(start 0.12065 -0.3048)
			(end 0.67945 -0.3048)
			(stroke
				(width 0.1)
				(type default)
			)
			(layer "F.Fab")
		)
		(fp_line
			(start 0.120396 0.3048)
			(end 0.120396 0.2794)
			(stroke
				(width 0.1)
				(type default)
			)
			(layer "F.Fab")
		)
		(fp_line
			(start 0.120396 0.2794)
			(end -0.12065 0.2794)
			(stroke
				(width 0.1)
				(type default)
			)
			(layer "F.Fab")
		)
		(fp_line
			(start -0.12065 0.3048)
			(end -0.67945 0.3048)
			(stroke
				(width 0.1)
				(type default)
			)
			(layer "F.Fab")
		)
		(fp_line
			(start -0.12065 0.2794)
			(end -0.12065 0.3048)
			(stroke
				(width 0.1)
				(type default)
			)
			(layer "F.Fab")
		)
		(fp_line
			(start -0.12065 -0.2794)
			(end 0.12065 -0.2794)
			(stroke
				(width 0.1)
				(type default)
			)
			(layer "F.Fab")
		)
		(fp_line
			(start -0.12065 -0.305054)
			(end -0.12065 -0.2794)
			(stroke
				(width 0.1)
				(type default)
			)
			(layer "F.Fab")
		)
		(fp_line
			(start -0.67945 0.3048)
			(end -0.67945 -0.305054)
			(stroke
				(width 0.1)
				(type default)
			)
			(layer "F.Fab")
		)
		(fp_line
			(start -0.67945 -0.305054)
			(end -0.12065 -0.305054)
			(stroke
				(width 0.1)
				(type default)
			)
			(layer "F.Fab")
		)
		(pad "1" smd circle
			(at -0.40005 0 180)
			(size 0 0)
			(layers "F.Cu" "F.Mask" "F.Paste")
			(net "PEX3_PCA9555_INT_R_N")
		)
		(pad "2" smd circle
			(at 0.40005 0 180)
			(size 0 0)
			(layers "F.Cu" "F.Mask" "F.Paste")
			(net "PEX3_PCA9555_INT_N")
		)
	)
	(footprint ""
		(layer "F.Cu")
		(at 387.580632 -102.888796)
		(property "Reference" "C692"
			(at 0 0 0)
			(layer "F.SilkS")
			(hide yes)
			(effects
				(font
					(size 1.27 1.27)
				)
			)
		)
		(property "Value" ""
			(at 0 0 0)
			(layer "F.Fab")
			(effects
				(font
					(size 1.27 1.27)
				)
			)
		)
		(duplicate_pad_numbers_are_jumpers no)
		(fp_line
			(start -0.299974 -0.150114)
			(end 0.299974 -0.150114)
			(stroke
				(width 0.1)
				(type default)
			)
			(layer "F.Fab")
		)
		(fp_line
			(start -0.299974 0.150114)
			(end -0.299974 -0.150114)
			(stroke
				(width 0.1)
				(type default)
			)
			(layer "F.Fab")
		)
		(fp_line
			(start 0.299974 -0.150114)
			(end 0.299974 0.150114)
			(stroke
				(width 0.1)
				(type default)
			)
			(layer "F.Fab")
		)
		(fp_line
			(start 0.299974 0.150114)
			(end -0.299974 0.150114)
			(stroke
				(width 0.1)
				(type default)
			)
			(layer "F.Fab")
		)
		(pad "1" smd rect
			(at -0.2667 0)
			(size 0.3048 0.381)
			(layers "F.Cu" "F.Mask" "F.Paste")
			(net "P5E_PEX3_STN1_TX_DP<18>")
		)
		(pad "2" smd rect
			(at 0.2667 0)
			(size 0.3048 0.381)
			(layers "F.Cu" "F.Mask" "F.Paste")
			(net "P5E_PEX3_STN1_TX_C_DP<18>")
		)
	)
	(footprint ""
		(layer "F.Cu")
		(at 132.41274 -118.378986 90)
		(property "Reference" "PC790"
			(at 0 0 90)
			(layer "F.SilkS")
			(hide yes)
			(effects
				(font
					(size 1.27 1.27)
				)
			)
		)
		(property "Value" ""
			(at 0 0 90)
			(layer "F.Fab")
			(effects
				(font
					(size 1.27 1.27)
				)
			)
		)
		(duplicate_pad_numbers_are_jumpers no)
		(fp_line
			(start 0.7874 -0.4064)
			(end 0.7874 0.4064)
			(stroke
				(width 0.1524)
				(type default)
			)
			(layer "F.SilkS")
		)
		(fp_line
			(start -0.7874 -0.4064)
			(end 0.7874 -0.4064)
			(stroke
				(width 0.1524)
				(type default)
			)
			(layer "F.SilkS")
		)
		(fp_line
			(start 0.7874 0.4064)
			(end -0.7874 0.4064)
			(stroke
				(width 0.1524)
				(type default)
			)
			(layer "F.SilkS")
		)
		(fp_line
			(start -0.7874 0.4064)
			(end -0.7874 -0.4064)
			(stroke
				(width 0.1524)
				(type default)
			)
			(layer "F.SilkS")
		)
		(fp_line
			(start -0.12065 -0.305054)
			(end -0.12065 -0.2794)
			(stroke
				(width 0.1)
				(type default)
			)
			(layer "F.Fab")
		)
		(fp_line
			(start -0.67945 -0.305054)
			(end -0.12065 -0.305054)
			(stroke
				(width 0.1)
				(type default)
			)
			(layer "F.Fab")
		)
		(fp_line
			(start 0.67945 -0.3048)
			(end 0.67945 0.3048)
			(stroke
				(width 0.1)
				(type default)
			)
			(layer "F.Fab")
		)
		(fp_line
			(start 0.12065 -0.3048)
			(end 0.67945 -0.3048)
			(stroke
				(width 0.1)
				(type default)
			)
			(layer "F.Fab")
		)
		(fp_line
			(start 0.12065 -0.2794)
			(end 0.12065 -0.3048)
			(stroke
				(width 0.1)
				(type default)
			)
			(layer "F.Fab")
		)
		(fp_line
			(start -0.12065 -0.2794)
			(end 0.12065 -0.2794)
			(stroke
				(width 0.1)
				(type default)
			)
			(layer "F.Fab")
		)
		(fp_line
			(start 0.120396 0.2794)
			(end -0.12065 0.2794)
			(stroke
				(width 0.1)
				(type default)
			)
			(layer "F.Fab")
		)
		(fp_line
			(start -0.12065 0.2794)
			(end -0.12065 0.3048)
			(stroke
				(width 0.1)
				(type default)
			)
			(layer "F.Fab")
		)
		(fp_line
			(start 0.67945 0.3048)
			(end 0.120396 0.3048)
			(stroke
				(width 0.1)
				(type default)
			)
			(layer "F.Fab")
		)
		(fp_line
			(start 0.120396 0.3048)
			(end 0.120396 0.2794)
			(stroke
				(width 0.1)
				(type default)
			)
			(layer "F.Fab")
		)
		(fp_line
			(start -0.12065 0.3048)
			(end -0.67945 0.3048)
			(stroke
				(width 0.1)
				(type default)
			)
			(layer "F.Fab")
		)
		(fp_line
			(start -0.67945 0.3048)
			(end -0.67945 -0.305054)
			(stroke
				(width 0.1)
				(type default)
			)
			(layer "F.Fab")
		)
		(pad "1" smd circle
			(at -0.40005 0 90)
			(size 0 0)
			(layers "F.Cu" "F.Mask" "F.Paste")
			(net "P3V3_NIC2_CO_GATE")
		)
		(pad "2" smd circle
			(at 0.40005 0 90)
			(size 0 0)
			(layers "F.Cu" "F.Mask" "F.Paste")
			(net "GND")
		)
	)
	(footprint ""
		(layer "F.Cu")
		(at 232.409746 -121.778268 180)
		(property "Reference" "PR6888"
			(at 0 0 180)
			(layer "F.SilkS")
			(hide yes)
			(effects
				(font
					(size 1.27 1.27)
				)
			)
		)
		(property "Value" ""
			(at 0 0 180)
			(layer "F.Fab")
			(effects
				(font
					(size 1.27 1.27)
				)
			)
		)
		(duplicate_pad_numbers_are_jumpers no)
		(fp_line
			(start 0.7874 0.4064)
			(end -0.7874 0.4064)
			(stroke
				(width 0.1524)
				(type default)
			)
			(layer "F.SilkS")
		)
		(fp_line
			(start 0.7874 -0.4064)
			(end 0.7874 0.4064)
			(stroke
				(width 0.1524)
				(type default)
			)
			(layer "F.SilkS")
		)
		(fp_line
			(start -0.7874 0.4064)
			(end -0.7874 -0.4064)
			(stroke
				(width 0.1524)
				(type default)
			)
			(layer "F.SilkS")
		)
		(fp_line
			(start -0.7874 -0.4064)
			(end 0.7874 -0.4064)
			(stroke
				(width 0.1524)
				(type default)
			)
			(layer "F.SilkS")
		)
		(fp_line
			(start 0.67945 0.3048)
			(end 0.120396 0.3048)
			(stroke
				(width 0.1)
				(type default)
			)
			(layer "F.Fab")
		)
		(fp_line
			(start 0.67945 -0.3048)
			(end 0.67945 0.3048)
			(stroke
				(width 0.1)
				(type default)
			)
			(layer "F.Fab")
		)
		(fp_line
			(start 0.12065 -0.2794)
			(end 0.12065 -0.3048)
			(stroke
				(width 0.1)
				(type default)
			)
			(layer "F.Fab")
		)
		(fp_line
			(start 0.12065 -0.3048)
			(end 0.67945 -0.3048)
			(stroke
				(width 0.1)
				(type default)
			)
			(layer "F.Fab")
		)
		(fp_line
			(start 0.120396 0.3048)
			(end 0.120396 0.2794)
			(stroke
				(width 0.1)
				(type default)
			)
			(layer "F.Fab")
		)
		(fp_line
			(start 0.120396 0.2794)
			(end -0.12065 0.2794)
			(stroke
				(width 0.1)
				(type default)
			)
			(layer "F.Fab")
		)
		(fp_line
			(start -0.12065 0.3048)
			(end -0.67945 0.3048)
			(stroke
				(width 0.1)
				(type default)
			)
			(layer "F.Fab")
		)
		(fp_line
			(start -0.12065 0.2794)
			(end -0.12065 0.3048)
			(stroke
				(width 0.1)
				(type default)
			)
			(layer "F.Fab")
		)
		(fp_line
			(start -0.12065 -0.2794)
			(end 0.12065 -0.2794)
			(stroke
				(width 0.1)
				(type default)
			)
			(layer "F.Fab")
		)
		(fp_line
			(start -0.12065 -0.305054)
			(end -0.12065 -0.2794)
			(stroke
				(width 0.1)
				(type default)
			)
			(layer "F.Fab")
		)
		(fp_line
			(start -0.67945 0.3048)
			(end -0.67945 -0.305054)
			(stroke
				(width 0.1)
				(type default)
			)
			(layer "F.Fab")
		)
		(fp_line
			(start -0.67945 -0.305054)
			(end -0.12065 -0.305054)
			(stroke
				(width 0.1)
				(type default)
			)
			(layer "F.Fab")
		)
		(pad "1" smd circle
			(at -0.40005 0 180)
			(size 0 0)
			(layers "F.Cu" "F.Mask" "F.Paste")
			(net "P12V_NIC3_CO_OV_FB")
		)
		(pad "2" smd circle
			(at 0.40005 0 180)
			(size 0 0)
			(layers "F.Cu" "F.Mask" "F.Paste")
			(net "P12V_NIC3_R")
		)
	)
	(footprint ""
		(layer "F.Cu")
		(at 336.042 -149.987 180)
		(property "Reference" "R4828"
			(at 0 0 180)
			(layer "F.SilkS")
			(hide yes)
			(effects
				(font
					(size 1.27 1.27)
				)
			)
		)
		(property "Value" ""
			(at 0 0 180)
			(layer "F.Fab")
			(effects
				(font
					(size 1.27 1.27)
				)
			)
		)
		(duplicate_pad_numbers_are_jumpers no)
		(fp_line
			(start 0.7874 0.4064)
			(end -0.7874 0.4064)
			(stroke
				(width 0.1524)
				(type default)
			)
			(layer "F.SilkS")
		)
		(fp_line
			(start 0.7874 -0.4064)
			(end 0.7874 0.4064)
			(stroke
				(width 0.1524)
				(type default)
			)
			(layer "F.SilkS")
		)
		(fp_line
			(start -0.7874 0.4064)
			(end -0.7874 -0.4064)
			(stroke
				(width 0.1524)
				(type default)
			)
			(layer "F.SilkS")
		)
		(fp_line
			(start -0.7874 -0.4064)
			(end 0.7874 -0.4064)
			(stroke
				(width 0.1524)
				(type default)
			)
			(layer "F.SilkS")
		)
		(fp_line
			(start 0.67945 0.3048)
			(end 0.120396 0.3048)
			(stroke
				(width 0.1)
				(type default)
			)
			(layer "F.Fab")
		)
		(fp_line
			(start 0.67945 -0.3048)
			(end 0.67945 0.3048)
			(stroke
				(width 0.1)
				(type default)
			)
			(layer "F.Fab")
		)
		(fp_line
			(start 0.12065 -0.2794)
			(end 0.12065 -0.3048)
			(stroke
				(width 0.1)
				(type default)
			)
			(layer "F.Fab")
		)
		(fp_line
			(start 0.12065 -0.3048)
			(end 0.67945 -0.3048)
			(stroke
				(width 0.1)
				(type default)
			)
			(layer "F.Fab")
		)
		(fp_line
			(start 0.120396 0.3048)
			(end 0.120396 0.2794)
			(stroke
				(width 0.1)
				(type default)
			)
			(layer "F.Fab")
		)
		(fp_line
			(start 0.120396 0.2794)
			(end -0.12065 0.2794)
			(stroke
				(width 0.1)
				(type default)
			)
			(layer "F.Fab")
		)
		(fp_line
			(start -0.12065 0.3048)
			(end -0.67945 0.3048)
			(stroke
				(width 0.1)
				(type default)
			)
			(layer "F.Fab")
		)
		(fp_line
			(start -0.12065 0.2794)
			(end -0.12065 0.3048)
			(stroke
				(width 0.1)
				(type default)
			)
			(layer "F.Fab")
		)
		(fp_line
			(start -0.12065 -0.2794)
			(end 0.12065 -0.2794)
			(stroke
				(width 0.1)
				(type default)
			)
			(layer "F.Fab")
		)
		(fp_line
			(start -0.12065 -0.305054)
			(end -0.12065 -0.2794)
			(stroke
				(width 0.1)
				(type default)
			)
			(layer "F.Fab")
		)
		(fp_line
			(start -0.67945 0.3048)
			(end -0.67945 -0.305054)
			(stroke
				(width 0.1)
				(type default)
			)
			(layer "F.Fab")
		)
		(fp_line
			(start -0.67945 -0.305054)
			(end -0.12065 -0.305054)
			(stroke
				(width 0.1)
				(type default)
			)
			(layer "F.Fab")
		)
		(pad "1" smd circle
			(at -0.40005 0 180)
			(size 0 0)
			(layers "F.Cu" "F.Mask" "F.Paste")
			(net "PCA9555_1_PEX3_A1")
		)
		(pad "2" smd circle
			(at 0.40005 0 180)
			(size 0 0)
			(layers "F.Cu" "F.Mask" "F.Paste")
			(net "P3V3_AUX")
		)
	)
	(footprint ""
		(layer "F.Cu")
		(at 335.154524 -343.952322 90)
		(property "Reference" "C530"
			(at 0 0 90)
			(layer "F.SilkS")
			(hide yes)
			(effects
				(font
					(size 1.27 1.27)
				)
			)
		)
		(property "Value" ""
			(at 0 0 90)
			(layer "F.Fab")
			(effects
				(font
					(size 1.27 1.27)
				)
			)
		)
		(duplicate_pad_numbers_are_jumpers no)
		(fp_line
			(start 0.299974 -0.150114)
			(end 0.299974 0.150114)
			(stroke
				(width 0.1)
				(type default)
			)
			(layer "F.Fab")
		)
		(fp_line
			(start -0.299974 -0.150114)
			(end 0.299974 -0.150114)
			(stroke
				(width 0.1)
				(type default)
			)
			(layer "F.Fab")
		)
		(fp_line
			(start 0.299974 0.150114)
			(end -0.299974 0.150114)
			(stroke
				(width 0.1)
				(type default)
			)
			(layer "F.Fab")
		)
		(fp_line
			(start -0.299974 0.150114)
			(end -0.299974 -0.150114)
			(stroke
				(width 0.1)
				(type default)
			)
			(layer "F.Fab")
		)
		(pad "1" smd rect
			(at -0.2667 0 90)
			(size 0.3048 0.381)
			(layers "F.Cu" "F.Mask" "F.Paste")
			(net "P5E_PEX2_STN5_TX_DN<90>")
		)
		(pad "2" smd rect
			(at 0.2667 0 90)
			(size 0.3048 0.381)
			(layers "F.Cu" "F.Mask" "F.Paste")
			(net "P5E_PEX2_STN5_TX_C_DN<90>")
		)
	)
)
